(kicad_pcb
	(version 20260206)
	(generator "pcbnew")
	(generator_version "10.0")
	(general
		(thickness 1.6)
		(legacy_teardrops no)
	)
	(paper "A4")
	(title_block
		(title "04192023_DAF0TMB3IC0_F0TG_MB_C_brd_V02_OCP.brd")
		(comment 1 "Grand Teton / footprints 6383-6389 of 8354")
	)
	(layers
		(0 "F.Cu" signal "TOP")
		(4 "In1.Cu" signal "GND")
		(6 "In2.Cu" signal "IN1")
		(8 "In3.Cu" signal "GND1")
		(10 "In4.Cu" signal "IN2")
		(12 "In5.Cu" signal "GND2")
		(14 "In6.Cu" signal "IN3")
		(16 "In7.Cu" signal "GND3")
		(18 "In8.Cu" signal "VCC")
		(20 "In9.Cu" signal "VCC1")
		(22 "In10.Cu" signal "GND4")
		(24 "In11.Cu" signal "IN4")
		(26 "In12.Cu" signal "GND5")
		(28 "In13.Cu" signal "IN5")
		(30 "In14.Cu" signal "GND6")
		(32 "In15.Cu" signal "IN6")
		(34 "In16.Cu" signal "GND7")
		(2 "B.Cu" signal "BOTTOM")
		(9 "F.Adhes" user "F.Adhesive")
		(11 "B.Adhes" user "B.Adhesive")
		(13 "F.Paste" user "Package Geometry/Pastemask Top")
		(15 "B.Paste" user "Package Geometry/Pastemask Bottom")
		(5 "F.SilkS" user "Ref Des/Silkscreen Top")
		(7 "B.SilkS" user "Ref Des/Silkscreen Bottom")
		(1 "F.Mask" user "Board Geometry/Soldermask Top")
		(3 "B.Mask" user "Board Geometry/Soldermask Bottom")
		(17 "Dwgs.User" user "User.Drawings")
		(19 "Cmts.User" user "User.Comments")
		(21 "Eco1.User" user "User.Eco1")
		(23 "Eco2.User" user "User.Eco2")
		(25 "Edge.Cuts" user "Board Geometry/Outline")
		(27 "Margin" user)
		(31 "F.CrtYd" user "Package Geometry/Place Bound Top")
		(29 "B.CrtYd" user "Package Geometry/Place Bound Bottom")
		(35 "F.Fab" user "Ref Des/Assembly Top")
		(33 "B.Fab" user "Ref Des/Assembly Bottom")
	)
	(footprint ""
		(layer "B.Cu")
		(at 428.087282 -436.414672 90)
		(property "Reference" "R4163"
			(at 0 0 90)
			(layer "B.SilkS")
			(hide yes)
			(effects
				(font
					(size 1.27 1.27)
				)
				(justify mirror)
			)
		)
		(property "Value" ""
			(at 0 0 90)
			(layer "B.Fab")
			(effects
				(font
					(size 1.27 1.27)
				)
				(justify mirror)
			)
		)
		(duplicate_pad_numbers_are_jumpers no)
		(fp_line
			(start 0.7874 -0.4064)
			(end -0.7874 -0.4064)
			(stroke
				(width 0.1524)
				(type default)
			)
			(layer "B.SilkS")
		)
		(fp_line
			(start -0.7874 -0.4064)
			(end -0.7874 0.4064)
			(stroke
				(width 0.1524)
				(type default)
			)
			(layer "B.SilkS")
		)
		(fp_line
			(start 0.7874 0.4064)
			(end 0.7874 -0.4064)
			(stroke
				(width 0.1524)
				(type default)
			)
			(layer "B.SilkS")
		)
		(fp_line
			(start -0.7874 0.4064)
			(end 0.7874 0.4064)
			(stroke
				(width 0.1524)
				(type default)
			)
			(layer "B.SilkS")
		)
		(fp_line
			(start 0.67945 -0.305054)
			(end 0.12065 -0.305054)
			(stroke
				(width 0.1)
				(type default)
			)
			(layer "B.Fab")
		)
		(fp_line
			(start 0.12065 -0.305054)
			(end 0.12065 -0.2794)
			(stroke
				(width 0.1)
				(type default)
			)
			(layer "B.Fab")
		)
		(fp_line
			(start -0.12065 -0.3048)
			(end -0.67945 -0.3048)
			(stroke
				(width 0.1)
				(type default)
			)
			(layer "B.Fab")
		)
		(fp_line
			(start -0.67945 -0.3048)
			(end -0.67945 0.3048)
			(stroke
				(width 0.1)
				(type default)
			)
			(layer "B.Fab")
		)
		(fp_line
			(start 0.12065 -0.2794)
			(end -0.12065 -0.2794)
			(stroke
				(width 0.1)
				(type default)
			)
			(layer "B.Fab")
		)
		(fp_line
			(start -0.12065 -0.2794)
			(end -0.12065 -0.3048)
			(stroke
				(width 0.1)
				(type default)
			)
			(layer "B.Fab")
		)
		(fp_line
			(start 0.12065 0.2794)
			(end 0.12065 0.3048)
			(stroke
				(width 0.1)
				(type default)
			)
			(layer "B.Fab")
		)
		(fp_line
			(start -0.120396 0.2794)
			(end 0.12065 0.2794)
			(stroke
				(width 0.1)
				(type default)
			)
			(layer "B.Fab")
		)
		(fp_line
			(start 0.67945 0.3048)
			(end 0.67945 -0.305054)
			(stroke
				(width 0.1)
				(type default)
			)
			(layer "B.Fab")
		)
		(fp_line
			(start 0.12065 0.3048)
			(end 0.67945 0.3048)
			(stroke
				(width 0.1)
				(type default)
			)
			(layer "B.Fab")
		)
		(fp_line
			(start -0.120396 0.3048)
			(end -0.120396 0.2794)
			(stroke
				(width 0.1)
				(type default)
			)
			(layer "B.Fab")
		)
		(fp_line
			(start -0.67945 0.3048)
			(end -0.120396 0.3048)
			(stroke
				(width 0.1)
				(type default)
			)
			(layer "B.Fab")
		)
		(pad "1" smd circle
			(at 0.40005 0 270)
			(size 0 0)
			(layers "B.Cu" "B.Mask" "B.Paste")
			(net "GPU_3V3IO_RSVD3")
		)
		(pad "2" smd circle
			(at -0.40005 0 270)
			(size 0 0)
			(layers "B.Cu" "B.Mask" "B.Paste")
			(net "GND")
		)
	)
	(footprint ""
		(layer "B.Cu")
		(at 201.12355 -116.971572 180)
		(property "Reference" "R3"
			(at 0 0 0)
			(layer "B.SilkS")
			(hide yes)
			(effects
				(font
					(size 1.27 1.27)
				)
				(justify mirror)
			)
		)
		(property "Value" ""
			(at 0 0 0)
			(layer "B.Fab")
			(effects
				(font
					(size 1.27 1.27)
				)
				(justify mirror)
			)
		)
		(duplicate_pad_numbers_are_jumpers no)
		(fp_line
			(start 0.7874 0.4064)
			(end 0.7874 -0.4064)
			(stroke
				(width 0.1524)
				(type default)
			)
			(layer "B.SilkS")
		)
		(fp_line
			(start 0.7874 -0.4064)
			(end -0.7874 -0.4064)
			(stroke
				(width 0.1524)
				(type default)
			)
			(layer "B.SilkS")
		)
		(fp_line
			(start -0.7874 0.4064)
			(end 0.7874 0.4064)
			(stroke
				(width 0.1524)
				(type default)
			)
			(layer "B.SilkS")
		)
		(fp_line
			(start -0.7874 -0.4064)
			(end -0.7874 0.4064)
			(stroke
				(width 0.1524)
				(type default)
			)
			(layer "B.SilkS")
		)
		(fp_line
			(start 0.67945 0.3048)
			(end 0.67945 -0.305054)
			(stroke
				(width 0.1)
				(type default)
			)
			(layer "B.Fab")
		)
		(fp_line
			(start 0.67945 -0.305054)
			(end 0.12065 -0.305054)
			(stroke
				(width 0.1)
				(type default)
			)
			(layer "B.Fab")
		)
		(fp_line
			(start 0.12065 0.3048)
			(end 0.67945 0.3048)
			(stroke
				(width 0.1)
				(type default)
			)
			(layer "B.Fab")
		)
		(fp_line
			(start 0.12065 0.2794)
			(end 0.12065 0.3048)
			(stroke
				(width 0.1)
				(type default)
			)
			(layer "B.Fab")
		)
		(fp_line
			(start 0.12065 -0.2794)
			(end -0.12065 -0.2794)
			(stroke
				(width 0.1)
				(type default)
			)
			(layer "B.Fab")
		)
		(fp_line
			(start 0.12065 -0.305054)
			(end 0.12065 -0.2794)
			(stroke
				(width 0.1)
				(type default)
			)
			(layer "B.Fab")
		)
		(fp_line
			(start -0.120396 0.3048)
			(end -0.120396 0.2794)
			(stroke
				(width 0.1)
				(type default)
			)
			(layer "B.Fab")
		)
		(fp_line
			(start -0.120396 0.2794)
			(end 0.12065 0.2794)
			(stroke
				(width 0.1)
				(type default)
			)
			(layer "B.Fab")
		)
		(fp_line
			(start -0.12065 -0.2794)
			(end -0.12065 -0.3048)
			(stroke
				(width 0.1)
				(type default)
			)
			(layer "B.Fab")
		)
		(fp_line
			(start -0.12065 -0.3048)
			(end -0.67945 -0.3048)
			(stroke
				(width 0.1)
				(type default)
			)
			(layer "B.Fab")
		)
		(fp_line
			(start -0.67945 0.3048)
			(end -0.120396 0.3048)
			(stroke
				(width 0.1)
				(type default)
			)
			(layer "B.Fab")
		)
		(fp_line
			(start -0.67945 -0.3048)
			(end -0.67945 0.3048)
			(stroke
				(width 0.1)
				(type default)
			)
			(layer "B.Fab")
		)
		(pad "1" smd circle
			(at 0.40005 0)
			(size 0 0)
			(layers "B.Cu" "B.Mask" "B.Paste")
			(net "RST_PERST_CPU1_SWB_1_N")
		)
		(pad "2" smd circle
			(at -0.40005 0)
			(size 0 0)
			(layers "B.Cu" "B.Mask" "B.Paste")
			(net "GND")
		)
	)
	(footprint ""
		(layer "B.Cu")
		(at 16.208502 -98.669348)
		(property "Reference" "C2032"
			(at 0 0 0)
			(layer "B.SilkS")
			(hide yes)
			(effects
				(font
					(size 1.27 1.27)
				)
				(justify mirror)
			)
		)
		(property "Value" ""
			(at 0 0 0)
			(layer "B.Fab")
			(effects
				(font
					(size 1.27 1.27)
				)
				(justify mirror)
			)
		)
		(duplicate_pad_numbers_are_jumpers no)
		(fp_line
			(start -0.7874 -0.4064)
			(end -0.7874 0.4064)
			(stroke
				(width 0.1524)
				(type default)
			)
			(layer "B.SilkS")
		)
		(fp_line
			(start -0.7874 0.4064)
			(end 0.7874 0.4064)
			(stroke
				(width 0.1524)
				(type default)
			)
			(layer "B.SilkS")
		)
		(fp_line
			(start 0.7874 -0.4064)
			(end -0.7874 -0.4064)
			(stroke
				(width 0.1524)
				(type default)
			)
			(layer "B.SilkS")
		)
		(fp_line
			(start 0.7874 0.4064)
			(end 0.7874 -0.4064)
			(stroke
				(width 0.1524)
				(type default)
			)
			(layer "B.SilkS")
		)
		(fp_line
			(start -0.67945 -0.3048)
			(end -0.67945 0.3048)
			(stroke
				(width 0.1)
				(type default)
			)
			(layer "B.Fab")
		)
		(fp_line
			(start -0.67945 0.3048)
			(end -0.120396 0.3048)
			(stroke
				(width 0.1)
				(type default)
			)
			(layer "B.Fab")
		)
		(fp_line
			(start -0.12065 -0.3048)
			(end -0.67945 -0.3048)
			(stroke
				(width 0.1)
				(type default)
			)
			(layer "B.Fab")
		)
		(fp_line
			(start -0.12065 -0.2794)
			(end -0.12065 -0.3048)
			(stroke
				(width 0.1)
				(type default)
			)
			(layer "B.Fab")
		)
		(fp_line
			(start -0.120396 0.2794)
			(end 0.12065 0.2794)
			(stroke
				(width 0.1)
				(type default)
			)
			(layer "B.Fab")
		)
		(fp_line
			(start -0.120396 0.3048)
			(end -0.120396 0.2794)
			(stroke
				(width 0.1)
				(type default)
			)
			(layer "B.Fab")
		)
		(fp_line
			(start 0.12065 -0.305054)
			(end 0.12065 -0.2794)
			(stroke
				(width 0.1)
				(type default)
			)
			(layer "B.Fab")
		)
		(fp_line
			(start 0.12065 -0.2794)
			(end -0.12065 -0.2794)
			(stroke
				(width 0.1)
				(type default)
			)
			(layer "B.Fab")
		)
		(fp_line
			(start 0.12065 0.2794)
			(end 0.12065 0.3048)
			(stroke
				(width 0.1)
				(type default)
			)
			(layer "B.Fab")
		)
		(fp_line
			(start 0.12065 0.3048)
			(end 0.67945 0.3048)
			(stroke
				(width 0.1)
				(type default)
			)
			(layer "B.Fab")
		)
		(fp_line
			(start 0.67945 -0.305054)
			(end 0.12065 -0.305054)
			(stroke
				(width 0.1)
				(type default)
			)
			(layer "B.Fab")
		)
		(fp_line
			(start 0.67945 0.3048)
			(end 0.67945 -0.305054)
			(stroke
				(width 0.1)
				(type default)
			)
			(layer "B.Fab")
		)
		(pad "1" smd circle
			(at 0.40005 0 180)
			(size 0 0)
			(layers "B.Cu" "B.Mask" "B.Paste")
			(net "P3V3_AUX_USB_HUB")
		)
		(pad "2" smd circle
			(at -0.40005 0 180)
			(size 0 0)
			(layers "B.Cu" "B.Mask" "B.Paste")
			(net "GND")
		)
	)
	(footprint ""
		(layer "B.Cu")
		(at 101.444044 -387.084062 -90)
		(property "Reference" "C103"
			(at 0 0 90)
			(layer "B.SilkS")
			(hide yes)
			(effects
				(font
					(size 1.27 1.27)
				)
				(justify mirror)
			)
		)
		(property "Value" ""
			(at 0 0 90)
			(layer "B.Fab")
			(effects
				(font
					(size 1.27 1.27)
				)
				(justify mirror)
			)
		)
		(duplicate_pad_numbers_are_jumpers no)
		(fp_line
			(start -1.524 0.762)
			(end 1.524 0.762)
			(stroke
				(width 0.1524)
				(type default)
			)
			(layer "B.SilkS")
		)
		(fp_line
			(start 1.524 0.762)
			(end 1.524 -0.762)
			(stroke
				(width 0.1524)
				(type default)
			)
			(layer "B.SilkS")
		)
		(fp_line
			(start -1.524 -0.762)
			(end -1.524 0.762)
			(stroke
				(width 0.1524)
				(type default)
			)
			(layer "B.SilkS")
		)
		(fp_line
			(start 1.524 -0.762)
			(end -1.524 -0.762)
			(stroke
				(width 0.1524)
				(type default)
			)
			(layer "B.SilkS")
		)
		(fp_line
			(start -1.1049 0.724916)
			(end -1.1049 -0.724916)
			(stroke
				(width 0.1)
				(type default)
			)
			(layer "B.Fab")
		)
		(fp_line
			(start 1.1049 0.724916)
			(end -1.1049 0.724916)
			(stroke
				(width 0.1)
				(type default)
			)
			(layer "B.Fab")
		)
		(fp_line
			(start -1.1049 -0.724916)
			(end 1.1049 -0.724916)
			(stroke
				(width 0.1)
				(type default)
			)
			(layer "B.Fab")
		)
		(fp_line
			(start 1.1049 -0.724916)
			(end 1.1049 0.724916)
			(stroke
				(width 0.1)
				(type default)
			)
			(layer "B.Fab")
		)
		(pad "1" smd rect
			(at 0.889 0 270)
			(size 1.016 1.27)
			(layers "B.Cu" "B.Mask" "B.Paste")
			(net "P1V8_CPU1_RT1_1A")
		)
		(pad "2" smd rect
			(at -0.889 0 270)
			(size 1.016 1.27)
			(layers "B.Cu" "B.Mask" "B.Paste")
			(net "GND")
		)
	)
	(footprint ""
		(layer "B.Cu")
		(at 208.461356 -377.666504)
		(property "Reference" "PR2510"
			(at 0 0 0)
			(layer "B.SilkS")
			(hide yes)
			(effects
				(font
					(size 1.27 1.27)
				)
				(justify mirror)
			)
		)
		(property "Value" ""
			(at 0 0 0)
			(layer "B.Fab")
			(effects
				(font
					(size 1.27 1.27)
				)
				(justify mirror)
			)
		)
		(duplicate_pad_numbers_are_jumpers no)
		(fp_line
			(start -0.7874 -0.4064)
			(end -0.7874 0.4064)
			(stroke
				(width 0.1524)
				(type default)
			)
			(layer "B.SilkS")
		)
		(fp_line
			(start -0.7874 0.4064)
			(end 0.7874 0.4064)
			(stroke
				(width 0.1524)
				(type default)
			)
			(layer "B.SilkS")
		)
		(fp_line
			(start 0.7874 -0.4064)
			(end -0.7874 -0.4064)
			(stroke
				(width 0.1524)
				(type default)
			)
			(layer "B.SilkS")
		)
		(fp_line
			(start 0.7874 0.4064)
			(end 0.7874 -0.4064)
			(stroke
				(width 0.1524)
				(type default)
			)
			(layer "B.SilkS")
		)
		(fp_line
			(start -0.67945 -0.3048)
			(end -0.67945 0.3048)
			(stroke
				(width 0.1)
				(type default)
			)
			(layer "B.Fab")
		)
		(fp_line
			(start -0.67945 0.3048)
			(end -0.120396 0.3048)
			(stroke
				(width 0.1)
				(type default)
			)
			(layer "B.Fab")
		)
		(fp_line
			(start -0.12065 -0.3048)
			(end -0.67945 -0.3048)
			(stroke
				(width 0.1)
				(type default)
			)
			(layer "B.Fab")
		)
		(fp_line
			(start -0.12065 -0.2794)
			(end -0.12065 -0.3048)
			(stroke
				(width 0.1)
				(type default)
			)
			(layer "B.Fab")
		)
		(fp_line
			(start -0.120396 0.2794)
			(end 0.12065 0.2794)
			(stroke
				(width 0.1)
				(type default)
			)
			(layer "B.Fab")
		)
		(fp_line
			(start -0.120396 0.3048)
			(end -0.120396 0.2794)
			(stroke
				(width 0.1)
				(type default)
			)
			(layer "B.Fab")
		)
		(fp_line
			(start 0.12065 -0.305054)
			(end 0.12065 -0.2794)
			(stroke
				(width 0.1)
				(type default)
			)
			(layer "B.Fab")
		)
		(fp_line
			(start 0.12065 -0.2794)
			(end -0.12065 -0.2794)
			(stroke
				(width 0.1)
				(type default)
			)
			(layer "B.Fab")
		)
		(fp_line
			(start 0.12065 0.2794)
			(end 0.12065 0.3048)
			(stroke
				(width 0.1)
				(type default)
			)
			(layer "B.Fab")
		)
		(fp_line
			(start 0.12065 0.3048)
			(end 0.67945 0.3048)
			(stroke
				(width 0.1)
				(type default)
			)
			(layer "B.Fab")
		)
		(fp_line
			(start 0.67945 -0.305054)
			(end 0.12065 -0.305054)
			(stroke
				(width 0.1)
				(type default)
			)
			(layer "B.Fab")
		)
		(fp_line
			(start 0.67945 0.3048)
			(end 0.67945 -0.305054)
			(stroke
				(width 0.1)
				(type default)
			)
			(layer "B.Fab")
		)
		(pad "1" smd circle
			(at 0.40005 0 180)
			(size 0 0)
			(layers "B.Cu" "B.Mask" "B.Paste")
			(net "P12V_HSC_ADC_P")
		)
		(pad "2" smd circle
			(at -0.40005 0 180)
			(size 0 0)
			(layers "B.Cu" "B.Mask" "B.Paste")
			(net "P12V_HSC_SENSE2_R1_P")
		)
	)
	(footprint ""
		(layer "B.Cu")
		(at 236.855 -240.411 -90)
		(property "Reference" "R362"
			(at 0 0 90)
			(layer "B.SilkS")
			(hide yes)
			(effects
				(font
					(size 1.27 1.27)
				)
				(justify mirror)
			)
		)
		(property "Value" ""
			(at 0 0 90)
			(layer "B.Fab")
			(effects
				(font
					(size 1.27 1.27)
				)
				(justify mirror)
			)
		)
		(duplicate_pad_numbers_are_jumpers no)
		(fp_line
			(start -0.7874 0.4064)
			(end 0.7874 0.4064)
			(stroke
				(width 0.1524)
				(type default)
			)
			(layer "B.SilkS")
		)
		(fp_line
			(start 0.7874 0.4064)
			(end 0.7874 -0.4064)
			(stroke
				(width 0.1524)
				(type default)
			)
			(layer "B.SilkS")
		)
		(fp_line
			(start -0.7874 -0.4064)
			(end -0.7874 0.4064)
			(stroke
				(width 0.1524)
				(type default)
			)
			(layer "B.SilkS")
		)
		(fp_line
			(start 0.7874 -0.4064)
			(end -0.7874 -0.4064)
			(stroke
				(width 0.1524)
				(type default)
			)
			(layer "B.SilkS")
		)
		(fp_line
			(start -0.67945 0.3048)
			(end -0.120396 0.3048)
			(stroke
				(width 0.1)
				(type default)
			)
			(layer "B.Fab")
		)
		(fp_line
			(start -0.120396 0.3048)
			(end -0.120396 0.2794)
			(stroke
				(width 0.1)
				(type default)
			)
			(layer "B.Fab")
		)
		(fp_line
			(start 0.12065 0.3048)
			(end 0.67945 0.3048)
			(stroke
				(width 0.1)
				(type default)
			)
			(layer "B.Fab")
		)
		(fp_line
			(start 0.67945 0.3048)
			(end 0.67945 -0.305054)
			(stroke
				(width 0.1)
				(type default)
			)
			(layer "B.Fab")
		)
		(fp_line
			(start -0.120396 0.2794)
			(end 0.12065 0.2794)
			(stroke
				(width 0.1)
				(type default)
			)
			(layer "B.Fab")
		)
		(fp_line
			(start 0.12065 0.2794)
			(end 0.12065 0.3048)
			(stroke
				(width 0.1)
				(type default)
			)
			(layer "B.Fab")
		)
		(fp_line
			(start -0.12065 -0.2794)
			(end -0.12065 -0.3048)
			(stroke
				(width 0.1)
				(type default)
			)
			(layer "B.Fab")
		)
		(fp_line
			(start 0.12065 -0.2794)
			(end -0.12065 -0.2794)
			(stroke
				(width 0.1)
				(type default)
			)
			(layer "B.Fab")
		)
		(fp_line
			(start -0.67945 -0.3048)
			(end -0.67945 0.3048)
			(stroke
				(width 0.1)
				(type default)
			)
			(layer "B.Fab")
		)
		(fp_line
			(start -0.12065 -0.3048)
			(end -0.67945 -0.3048)
			(stroke
				(width 0.1)
				(type default)
			)
			(layer "B.Fab")
		)
		(fp_line
			(start 0.12065 -0.305054)
			(end 0.12065 -0.2794)
			(stroke
				(width 0.1)
				(type default)
			)
			(layer "B.Fab")
		)
		(fp_line
			(start 0.67945 -0.305054)
			(end 0.12065 -0.305054)
			(stroke
				(width 0.1)
				(type default)
			)
			(layer "B.Fab")
		)
		(pad "1" smd circle
			(at 0.40005 0 90)
			(size 0 0)
			(layers "B.Cu" "B.Mask" "B.Paste")
			(net "PVDD11_S3_P1")
		)
		(pad "2" smd circle
			(at -0.40005 0 90)
			(size 0 0)
			(layers "B.Cu" "B.Mask" "B.Paste")
			(net "SMB_APML_CPU1_SCL")
		)
	)
	(footprint ""
		(layer "B.Cu")
		(at 97.906332 -386.766562 90)
		(property "Reference" "C289"
			(at 0 0 90)
			(layer "B.SilkS")
			(hide yes)
			(effects
				(font
					(size 1.27 1.27)
				)
				(justify mirror)
			)
		)
		(property "Value" ""
			(at 0 0 90)
			(layer "B.Fab")
			(effects
				(font
					(size 1.27 1.27)
				)
				(justify mirror)
			)
		)
		(duplicate_pad_numbers_are_jumpers no)
		(fp_line
			(start 0.299974 -0.150114)
			(end -0.299974 -0.150114)
			(stroke
				(width 0.1)
				(type default)
			)
			(layer "B.Fab")
		)
		(fp_line
			(start -0.299974 -0.150114)
			(end -0.299974 0.150114)
			(stroke
				(width 0.1)
				(type default)
			)
			(layer "B.Fab")
		)
		(fp_line
			(start 0.299974 0.150114)
			(end 0.299974 -0.150114)
			(stroke
				(width 0.1)
				(type default)
			)
			(layer "B.Fab")
		)
		(fp_line
			(start -0.299974 0.150114)
			(end 0.299974 0.150114)
			(stroke
				(width 0.1)
				(type default)
			)
			(layer "B.Fab")
		)
		(pad "1" smd rect
			(at 0.2667 0 270)
			(size 0.3048 0.381)
			(layers "B.Cu" "B.Mask" "B.Paste")
			(net "P0V9_CPU1_RT1_2A")
		)
		(pad "2" smd rect
			(at -0.2667 0 270)
			(size 0.3048 0.381)
			(layers "B.Cu" "B.Mask" "B.Paste")
			(net "GND")
		)
	)
)
